# SCM (Grand Teton) — schematic netlist excerpt (pin names and nets, part order shuffled) for the footprints in the layout excerpt that follows; sources: Cadence DE-HDL packaged netlist, KiCad conversion of 12092022_DA0F0TMDCD0_F0T_Management_Board_D_brd_V3_OCP.brd

J11  PICOPROBE_BXA  DELTA-L 4.0 EMPTY  pkg TRIANG_LAUNCH_3PXB  page 58
  \1_p\  = 85_5INCH_IN1_DN
  \2_n\  = 85_5INCH_IN1_DP
  \3_g\  = GND_P1

(kicad_pcb
	(version 20260206)
	(generator "pcbnew")
	(generator_version "10.0")
	(general
		(thickness 1.6)
		(legacy_teardrops no)
	)
	(paper "A4")
	(title_block
		(title "12092022_DA0F0TMDCD0_F0T_Management_Board_D_brd_V3_OCP.brd")
		(comment 1 "Grand Teton / footprints 861-861 of 1440")
	)
	(layers
		(0 "F.Cu" signal "TOP")
		(4 "In1.Cu" signal "GND")
		(6 "In2.Cu" signal "IN1")
		(8 "In3.Cu" signal "GND1")
		(10 "In4.Cu" signal "IN2")
		(12 "In5.Cu" signal "VCC")
		(14 "In6.Cu" signal "VCC1")
		(16 "In7.Cu" signal "IN3")
		(18 "In8.Cu" signal "GND2")
		(20 "In9.Cu" signal "IN4")
		(22 "In10.Cu" signal "GND3")
		(2 "B.Cu" signal "BOTTOM")
		(9 "F.Adhes" user "F.Adhesive")
		(11 "B.Adhes" user "B.Adhesive")
		(13 "F.Paste" user "Package Geometry/Pastemask Top")
		(15 "B.Paste" user "Package Geometry/Pastemask Bottom")
		(5 "F.SilkS" user "Ref Des/Silkscreen Top")
		(7 "B.SilkS" user "Ref Des/Silkscreen Bottom")
		(1 "F.Mask" user "Board Geometry/Soldermask Top")
		(3 "B.Mask" user "Board Geometry/Soldermask Bottom")
		(17 "Dwgs.User" user "User.Drawings")
		(19 "Cmts.User" user "User.Comments")
		(21 "Eco1.User" user "User.Eco1")
		(23 "Eco2.User" user "User.Eco2")
		(25 "Edge.Cuts" user "Board Geometry/Outline")
		(27 "Margin" user)
		(31 "F.CrtYd" user "Package Geometry/Place Bound Top")
		(29 "B.CrtYd" user "Package Geometry/Place Bound Bottom")
		(35 "F.Fab" user "Ref Des/Assembly Top")
		(33 "B.Fab" user "Ref Des/Assembly Bottom")
	)
	(footprint ""
		(layer "B.Cu")
		(at 95.926656 53.375814 90)
		(property "Reference" "J11"
			(at -0.980186 -2.862326 270)
			(unlocked yes)
			(layer "B.SilkS")
			(effects
				(font
					(size 0.7874 0.5842)
					(thickness 0.1524)
				)
				(justify left mirror)
			)
		)
		(property "Value" ""
			(at 0 0 90)
			(layer "B.Fab")
			(effects
				(font
					(size 1.27 1.27)
				)
				(justify mirror)
			)
		)
		(duplicate_pad_numbers_are_jumpers no)
		(fp_line
			(start 1.2192 -2.1082)
			(end -1.2192 -2.1082)
			(stroke
				(width 0.1524)
				(type default)
			)
			(layer "B.SilkS")
		)
		(fp_line
			(start -1.2192 -2.1082)
			(end -1.2192 -0.801624)
			(stroke
				(width 0.1524)
				(type default)
			)
			(layer "B.SilkS")
		)
		(fp_line
			(start -1.2192 0.866394)
			(end -1.2192 2.1082)
			(stroke
				(width 0.1524)
				(type default)
			)
			(layer "B.SilkS")
		)
		(fp_line
			(start 1.2192 2.1082)
			(end 1.2192 -2.1082)
			(stroke
				(width 0.1524)
				(type default)
			)
			(layer "B.SilkS")
		)
		(fp_line
			(start -1.2192 2.1082)
			(end 1.2192 2.1082)
			(stroke
				(width 0.1524)
				(type default)
			)
			(layer "B.SilkS")
		)
		(pad "" np_thru_hole circle
			(at -3.4671 -1.27)
			(size 1.0414 1.0414)
			(drill 1.0414)
			(layers "*.Cu" "*.Mask")
			(clearance 0.381)
			(thermal_gap 0.381)
		)
		(pad "" np_thru_hole circle
			(at -3.4671 1.27)
			(size 1.0414 1.0414)
			(drill 1.0414)
			(layers "*.Cu" "*.Mask")
			(clearance 0.381)
			(thermal_gap 0.381)
		)
		(pad "" np_thru_hole circle
			(at 2.8829 -1.27)
			(size 1.0414 1.0414)
			(drill 1.0414)
			(layers "*.Cu" "*.Mask")
			(clearance 0.381)
			(thermal_gap 0.381)
		)
		(pad "" np_thru_hole circle
			(at 2.8829 1.27)
			(size 1.0414 1.0414)
			(drill 1.0414)
			(layers "*.Cu" "*.Mask")
			(clearance 0.381)
			(thermal_gap 0.381)
		)
		(pad "1" smd rect
			(at -0.8255 -0.249936)
			(size 0.3048 0.508)
			(layers "B.Cu" "B.Mask" "B.Paste")
			(net "85_5INCH_IN1_DN")
		)
		(pad "2" smd rect
			(at -0.8255 0.249936)
			(size 0.3048 0.508)
			(layers "B.Cu" "B.Mask" "B.Paste")
			(net "85_5INCH_IN1_DP")
		)
		(pad "3" smd circle
			(at 0 0 270)
			(size 0 0)
			(layers "B.Cu" "B.Mask" "B.Paste")
			(net "GND_P1")
		)
		(zone
			(layers "F.Cu" "B.Cu" "In1.Cu" "In2.Cu" "In3.Cu" "In4.Cu" "In5.Cu" "In6.Cu"
				"In7.Cu" "In8.Cu" "In9.Cu" "In10.Cu"
			)
			(hatch none 0.5)
			(connect_pads
				(clearance 0)
			)
			(min_thickness 0.25)
			(keepout
				(tracks not_allowed)
				(vias allowed)
				(pads allowed)
				(copperpour not_allowed)
				(footprints allowed)
			)
			(placement
				(enabled no)
				(sheetname "")
			)
			(fill
				(thermal_gap 0.5)
				(thermal_bridge_width 0.5)
				(island_removal_mode 0)
			)
			(polygon
				(pts
					(arc
						(start 95.583756 50.492914)
						(mid 93.729556 50.492914)
						(end 95.583756 50.492914)
					)
				)
			)
		)
		(zone
			(layers "F.Cu" "B.Cu" "In1.Cu" "In2.Cu" "In3.Cu" "In4.Cu" "In5.Cu" "In6.Cu"
				"In7.Cu" "In8.Cu" "In9.Cu" "In10.Cu"
			)
			(hatch none 0.5)
			(connect_pads
				(clearance 0)
			)
			(min_thickness 0.25)
			(keepout
				(tracks not_allowed)
				(vias allowed)
				(pads allowed)
				(copperpour not_allowed)
				(footprints allowed)
			)
			(placement
				(enabled no)
				(sheetname "")
			)
			(fill
				(thermal_gap 0.5)
				(thermal_bridge_width 0.5)
				(island_removal_mode 0)
			)
			(polygon
				(pts
					(arc
						(start 95.583756 56.842914)
						(mid 93.729556 56.842914)
						(end 95.583756 56.842914)
					)
				)
			)
		)
		(zone
			(layers "F.Cu" "B.Cu" "In1.Cu" "In2.Cu" "In3.Cu" "In4.Cu" "In5.Cu" "In6.Cu"
				"In7.Cu" "In8.Cu" "In9.Cu" "In10.Cu"
			)
			(hatch none 0.5)
			(connect_pads
				(clearance 0)
			)
			(min_thickness 0.25)
			(keepout
				(tracks not_allowed)
				(vias allowed)
				(pads allowed)
				(copperpour not_allowed)
				(footprints allowed)
			)
			(placement
				(enabled no)
				(sheetname "")
			)
			(fill
				(thermal_gap 0.5)
				(thermal_bridge_width 0.5)
				(island_removal_mode 0)
			)
			(polygon
				(pts
					(arc
						(start 98.123756 50.492914)
						(mid 96.269556 50.492914)
						(end 98.123756 50.492914)
					)
				)
			)
		)
		(zone
			(layers "F.Cu" "B.Cu" "In1.Cu" "In2.Cu" "In3.Cu" "In4.Cu" "In5.Cu" "In6.Cu"
				"In7.Cu" "In8.Cu" "In9.Cu" "In10.Cu"
			)
			(hatch none 0.5)
			(connect_pads
				(clearance 0)
			)
			(min_thickness 0.25)
			(keepout
				(tracks not_allowed)
				(vias allowed)
				(pads allowed)
				(copperpour not_allowed)
				(footprints allowed)
			)
			(placement
				(enabled no)
				(sheetname "")
			)
			(fill
				(thermal_gap 0.5)
				(thermal_bridge_width 0.5)
				(island_removal_mode 0)
			)
			(polygon
				(pts
					(arc
						(start 98.123756 56.842914)
						(mid 96.269556 56.842914)
						(end 98.123756 56.842914)
					)
				)
			)
		)
		(zone
			(layer "B.Cu")
			(hatch none 0.5)
			(connect_pads
				(clearance 0)
			)
			(min_thickness 0.25)
			(keepout
				(tracks not_allowed)
				(vias allowed)
				(pads allowed)
				(copperpour not_allowed)
				(footprints allowed)
			)
			(placement
				(enabled no)
				(sheetname "")
			)
			(fill
				(thermal_gap 0.5)
				(thermal_bridge_width 0.5)
				(island_removal_mode 0)
			)
			(polygon
				(pts
					(xy 95.378016 54.493414) (xy 95.47352 54.493414) (xy 95.47352 53.896514) (xy 95.87992 53.896514)
					(xy 95.87992 54.493414) (xy 95.973392 54.493414) (xy 95.973392 53.896514) (xy 96.379792 53.896514)
					(xy 96.379792 54.493414) (xy 96.475296 54.493414) (xy 96.475296 53.794914) (xy 95.378016 53.794914)
				)
			)
		)
	)
)
